# T6G (Grand Teton) — schematic netlist excerpt (pin names and nets, part order shuffled) for the footprints in the layout excerpt that follows; sources: Cadence DE-HDL packaged netlist, KiCad conversion of 04192023_DAF0TMB3IC0_F0TG_MB_C_brd_V02_OCP.brd

C8246  Q_CAP  1000PF 50V 5% EMPTY  pkg 0402  page 210 : A = PWRGD_PVDDCR_SOC_P1_R ; B = GND
R1570  Q_RES  49.9 1% CHIP  pkg 0402LF  page 88 : A = I3C_SPD_DDRAF_CPU0_SCL ; B = I3C_SPD_DDRC_CPU0_SCL
R695  Q_RES  22 1% CHIP  pkg 0201LF  page 353 : A = SMB_RT_CPU1_P3_ROM_MUX_1D_SCL ; B = SMB_RT_CPU1_P3_ROM_MUX_1D_R_SCL

(kicad_pcb
	(version 20260206)
	(generator "pcbnew")
	(generator_version "10.0")
	(general
		(thickness 1.6)
		(legacy_teardrops no)
	)
	(paper "A4")
	(title_block
		(title "04192023_DAF0TMB3IC0_F0TG_MB_C_brd_V02_OCP.brd")
		(comment 1 "Grand Teton / footprints 5570-5572 of 8354")
	)
	(layers
		(0 "F.Cu" signal "TOP")
		(4 "In1.Cu" signal "GND")
		(6 "In2.Cu" signal "IN1")
		(8 "In3.Cu" signal "GND1")
		(10 "In4.Cu" signal "IN2")
		(12 "In5.Cu" signal "GND2")
		(14 "In6.Cu" signal "IN3")
		(16 "In7.Cu" signal "GND3")
		(18 "In8.Cu" signal "VCC")
		(20 "In9.Cu" signal "VCC1")
		(22 "In10.Cu" signal "GND4")
		(24 "In11.Cu" signal "IN4")
		(26 "In12.Cu" signal "GND5")
		(28 "In13.Cu" signal "IN5")
		(30 "In14.Cu" signal "GND6")
		(32 "In15.Cu" signal "IN6")
		(34 "In16.Cu" signal "GND7")
		(2 "B.Cu" signal "BOTTOM")
		(9 "F.Adhes" user "F.Adhesive")
		(11 "B.Adhes" user "B.Adhesive")
		(13 "F.Paste" user "Package Geometry/Pastemask Top")
		(15 "B.Paste" user "Package Geometry/Pastemask Bottom")
		(5 "F.SilkS" user "Ref Des/Silkscreen Top")
		(7 "B.SilkS" user "Ref Des/Silkscreen Bottom")
		(1 "F.Mask" user "Board Geometry/Soldermask Top")
		(3 "B.Mask" user "Board Geometry/Soldermask Bottom")
		(17 "Dwgs.User" user "User.Drawings")
		(19 "Cmts.User" user "User.Comments")
		(21 "Eco1.User" user "User.Eco1")
		(23 "Eco2.User" user "User.Eco2")
		(25 "Edge.Cuts" user "Board Geometry/Outline")
		(27 "Margin" user)
		(31 "F.CrtYd" user "Package Geometry/Place Bound Top")
		(29 "B.CrtYd" user "Package Geometry/Place Bound Bottom")
		(35 "F.Fab" user "Ref Des/Assembly Top")
		(33 "B.Fab" user "Ref Des/Assembly Bottom")
	)
	(footprint ""
		(layer "B.Cu")
		(at 113.17478 -408.618436 90)
		(property "Reference" "R695"
			(at 0 0 90)
			(layer "B.SilkS")
			(hide yes)
			(effects
				(font
					(size 1.27 1.27)
				)
				(justify mirror)
			)
		)
		(property "Value" ""
			(at 0 0 90)
			(layer "B.Fab")
			(effects
				(font
					(size 1.27 1.27)
				)
				(justify mirror)
			)
		)
		(duplicate_pad_numbers_are_jumpers no)
		(fp_line
			(start 0.32512 -0.175006)
			(end -0.32512 -0.175006)
			(stroke
				(width 0.1)
				(type default)
			)
			(layer "B.Fab")
		)
		(fp_line
			(start -0.32512 -0.175006)
			(end -0.32512 0.175006)
			(stroke
				(width 0.1)
				(type default)
			)
			(layer "B.Fab")
		)
		(fp_line
			(start 0.32512 0.175006)
			(end 0.32512 -0.175006)
			(stroke
				(width 0.1)
				(type default)
			)
			(layer "B.Fab")
		)
		(fp_line
			(start -0.32512 0.175006)
			(end 0.32512 0.175006)
			(stroke
				(width 0.1)
				(type default)
			)
			(layer "B.Fab")
		)
		(pad "1" smd rect
			(at 0.2667 0 270)
			(size 0.3048 0.381)
			(layers "B.Cu" "B.Mask" "B.Paste")
			(net "SMB_RT_CPU1_P3_ROM_MUX_1D_SCL")
		)
		(pad "2" smd rect
			(at -0.2667 0 90)
			(size 0.3048 0.381)
			(layers "B.Cu" "B.Mask" "B.Paste")
			(net "SMB_RT_CPU1_P3_ROM_MUX_1D_R_SCL")
		)
	)
	(footprint ""
		(layer "B.Cu")
		(at 291.52469 -194.893946 180)
		(property "Reference" "R1570"
			(at 0 0 0)
			(layer "B.SilkS")
			(hide yes)
			(effects
				(font
					(size 1.27 1.27)
				)
				(justify mirror)
			)
		)
		(property "Value" ""
			(at 0 0 0)
			(layer "B.Fab")
			(effects
				(font
					(size 1.27 1.27)
				)
				(justify mirror)
			)
		)
		(duplicate_pad_numbers_are_jumpers no)
		(fp_line
			(start 0.7874 0.4064)
			(end 0.7874 -0.4064)
			(stroke
				(width 0.1524)
				(type default)
			)
			(layer "B.SilkS")
		)
		(fp_line
			(start 0.7874 -0.4064)
			(end -0.7874 -0.4064)
			(stroke
				(width 0.1524)
				(type default)
			)
			(layer "B.SilkS")
		)
		(fp_line
			(start -0.7874 0.4064)
			(end 0.7874 0.4064)
			(stroke
				(width 0.1524)
				(type default)
			)
			(layer "B.SilkS")
		)
		(fp_line
			(start -0.7874 -0.4064)
			(end -0.7874 0.4064)
			(stroke
				(width 0.1524)
				(type default)
			)
			(layer "B.SilkS")
		)
		(fp_line
			(start 0.67945 0.3048)
			(end 0.67945 -0.305054)
			(stroke
				(width 0.1)
				(type default)
			)
			(layer "B.Fab")
		)
		(fp_line
			(start 0.67945 -0.305054)
			(end 0.12065 -0.305054)
			(stroke
				(width 0.1)
				(type default)
			)
			(layer "B.Fab")
		)
		(fp_line
			(start 0.12065 0.3048)
			(end 0.67945 0.3048)
			(stroke
				(width 0.1)
				(type default)
			)
			(layer "B.Fab")
		)
		(fp_line
			(start 0.12065 0.2794)
			(end 0.12065 0.3048)
			(stroke
				(width 0.1)
				(type default)
			)
			(layer "B.Fab")
		)
		(fp_line
			(start 0.12065 -0.2794)
			(end -0.12065 -0.2794)
			(stroke
				(width 0.1)
				(type default)
			)
			(layer "B.Fab")
		)
		(fp_line
			(start 0.12065 -0.305054)
			(end 0.12065 -0.2794)
			(stroke
				(width 0.1)
				(type default)
			)
			(layer "B.Fab")
		)
		(fp_line
			(start -0.120396 0.3048)
			(end -0.120396 0.2794)
			(stroke
				(width 0.1)
				(type default)
			)
			(layer "B.Fab")
		)
		(fp_line
			(start -0.120396 0.2794)
			(end 0.12065 0.2794)
			(stroke
				(width 0.1)
				(type default)
			)
			(layer "B.Fab")
		)
		(fp_line
			(start -0.12065 -0.2794)
			(end -0.12065 -0.3048)
			(stroke
				(width 0.1)
				(type default)
			)
			(layer "B.Fab")
		)
		(fp_line
			(start -0.12065 -0.3048)
			(end -0.67945 -0.3048)
			(stroke
				(width 0.1)
				(type default)
			)
			(layer "B.Fab")
		)
		(fp_line
			(start -0.67945 0.3048)
			(end -0.120396 0.3048)
			(stroke
				(width 0.1)
				(type default)
			)
			(layer "B.Fab")
		)
		(fp_line
			(start -0.67945 -0.3048)
			(end -0.67945 0.3048)
			(stroke
				(width 0.1)
				(type default)
			)
			(layer "B.Fab")
		)
		(pad "1" smd circle
			(at 0.40005 0)
			(size 0 0)
			(layers "B.Cu" "B.Mask" "B.Paste")
			(net "I3C_SPD_DDRAF_CPU0_SCL")
		)
		(pad "2" smd circle
			(at -0.40005 0)
			(size 0 0)
			(layers "B.Cu" "B.Mask" "B.Paste")
			(net "I3C_SPD_DDRC_CPU0_SCL")
		)
	)
	(footprint ""
		(layer "B.Cu")
		(at 90.209878 -145.90141)
		(property "Reference" "C8246"
			(at 0 0 0)
			(layer "B.SilkS")
			(hide yes)
			(effects
				(font
					(size 1.27 1.27)
				)
				(justify mirror)
			)
		)
		(property "Value" ""
			(at 0 0 0)
			(layer "B.Fab")
			(effects
				(font
					(size 1.27 1.27)
				)
				(justify mirror)
			)
		)
		(duplicate_pad_numbers_are_jumpers no)
		(fp_line
			(start -0.7874 -0.4064)
			(end -0.7874 0.4064)
			(stroke
				(width 0.1524)
				(type default)
			)
			(layer "B.SilkS")
		)
		(fp_line
			(start -0.7874 0.4064)
			(end 0.7874 0.4064)
			(stroke
				(width 0.1524)
				(type default)
			)
			(layer "B.SilkS")
		)
		(fp_line
			(start 0.7874 -0.4064)
			(end -0.7874 -0.4064)
			(stroke
				(width 0.1524)
				(type default)
			)
			(layer "B.SilkS")
		)
		(fp_line
			(start 0.7874 0.4064)
			(end 0.7874 -0.4064)
			(stroke
				(width 0.1524)
				(type default)
			)
			(layer "B.SilkS")
		)
		(fp_line
			(start -0.67945 -0.3048)
			(end -0.67945 0.3048)
			(stroke
				(width 0.1)
				(type default)
			)
			(layer "B.Fab")
		)
		(fp_line
			(start -0.67945 0.3048)
			(end -0.120396 0.3048)
			(stroke
				(width 0.1)
				(type default)
			)
			(layer "B.Fab")
		)
		(fp_line
			(start -0.12065 -0.3048)
			(end -0.67945 -0.3048)
			(stroke
				(width 0.1)
				(type default)
			)
			(layer "B.Fab")
		)
		(fp_line
			(start -0.12065 -0.2794)
			(end -0.12065 -0.3048)
			(stroke
				(width 0.1)
				(type default)
			)
			(layer "B.Fab")
		)
		(fp_line
			(start -0.120396 0.2794)
			(end 0.12065 0.2794)
			(stroke
				(width 0.1)
				(type default)
			)
			(layer "B.Fab")
		)
		(fp_line
			(start -0.120396 0.3048)
			(end -0.120396 0.2794)
			(stroke
				(width 0.1)
				(type default)
			)
			(layer "B.Fab")
		)
		(fp_line
			(start 0.12065 -0.305054)
			(end 0.12065 -0.2794)
			(stroke
				(width 0.1)
				(type default)
			)
			(layer "B.Fab")
		)
		(fp_line
			(start 0.12065 -0.2794)
			(end -0.12065 -0.2794)
			(stroke
				(width 0.1)
				(type default)
			)
			(layer "B.Fab")
		)
		(fp_line
			(start 0.12065 0.2794)
			(end 0.12065 0.3048)
			(stroke
				(width 0.1)
				(type default)
			)
			(layer "B.Fab")
		)
		(fp_line
			(start 0.12065 0.3048)
			(end 0.67945 0.3048)
			(stroke
				(width 0.1)
				(type default)
			)
			(layer "B.Fab")
		)
		(fp_line
			(start 0.67945 -0.305054)
			(end 0.12065 -0.305054)
			(stroke
				(width 0.1)
				(type default)
			)
			(layer "B.Fab")
		)
		(fp_line
			(start 0.67945 0.3048)
			(end 0.67945 -0.305054)
			(stroke
				(width 0.1)
				(type default)
			)
			(layer "B.Fab")
		)
		(pad "1" smd circle
			(at 0.40005 0 180)
			(size 0 0)
			(layers "B.Cu" "B.Mask" "B.Paste")
			(net "PWRGD_PVDDCR_SOC_P1_R")
		)
		(pad "2" smd circle
			(at -0.40005 0 180)
			(size 0 0)
			(layers "B.Cu" "B.Mask" "B.Paste")
			(net "GND")
		)
	)
)
